# S9S_MB_2U (Grand Teton) — schematic netlist excerpt (pin names and nets, part order shuffled) for the footprints in the layout excerpt that follows; sources: Cadence DE-HDL packaged netlist, KiCad conversion of 03242023_DA0F0TMBIJ0_F0T_Motherboard_J_brd_V01_OCP.brd

U30  PCA9517AD  IC  pkg SOIC8  page 236
  VCCA  = PVNN_TERM_CPU0
  SCLA  = SMB_S3M_CPU0_R_SCL
  SDAA  = SMB_S3M_CPU0_R_SDA
  GND  = GND
  ENABLE  = TP_SMB_S3M_CPU0_EN
  SDAB  = SMB_S3M_CPU0_3V3AUX_SDA
  SCLB  = SMB_S3M_CPU0_3V3AUX_SCL
  VCCB  = P3V3_AUX

R984  Q_RES  33.2 1% CHIP  pkg 0402LF  page 222 : A = FM_PVCCFA_EHV_FIVRA_CPU0_R_EN ; B = FM_PVCCFA_EHV_FIVRA_CPU0_EN

(kicad_pcb
	(version 20260206)
	(generator "pcbnew")
	(generator_version "10.0")
	(general
		(thickness 1.6)
		(legacy_teardrops no)
	)
	(paper "A4")
	(title_block
		(title "03242023_DA0F0TMBIJ0_F0T_Motherboard_J_brd_V01_OCP.brd")
		(comment 1 "Grand Teton / footprints 1110-1111 of 6105")
	)
	(layers
		(0 "F.Cu" signal "TOP")
		(4 "In1.Cu" signal "GND")
		(6 "In2.Cu" signal "IN1")
		(8 "In3.Cu" signal "GND1")
		(10 "In4.Cu" signal "IN2")
		(12 "In5.Cu" signal "GND2")
		(14 "In6.Cu" signal "IN3")
		(16 "In7.Cu" signal "GND3")
		(18 "In8.Cu" signal "VCC")
		(20 "In9.Cu" signal "VCC1")
		(22 "In10.Cu" signal "GND4")
		(24 "In11.Cu" signal "IN4")
		(26 "In12.Cu" signal "GND5")
		(28 "In13.Cu" signal "IN5")
		(30 "In14.Cu" signal "GND6")
		(32 "In15.Cu" signal "IN6")
		(34 "In16.Cu" signal "GND7")
		(2 "B.Cu" signal "BOTTOM")
		(9 "F.Adhes" user "F.Adhesive")
		(11 "B.Adhes" user "B.Adhesive")
		(13 "F.Paste" user "Package Geometry/Pastemask Top")
		(15 "B.Paste" user "Package Geometry/Pastemask Bottom")
		(5 "F.SilkS" user "Ref Des/Silkscreen Top")
		(7 "B.SilkS" user "Ref Des/Silkscreen Bottom")
		(1 "F.Mask" user "Board Geometry/Soldermask Top")
		(3 "B.Mask" user "Board Geometry/Soldermask Bottom")
		(17 "Dwgs.User" user "User.Drawings")
		(19 "Cmts.User" user "User.Comments")
		(21 "Eco1.User" user "User.Eco1")
		(23 "Eco2.User" user "User.Eco2")
		(25 "Edge.Cuts" user "Board Geometry/Outline")
		(27 "Margin" user)
		(31 "F.CrtYd" user "Package Geometry/Place Bound Top")
		(29 "B.CrtYd" user "Package Geometry/Place Bound Bottom")
		(35 "F.Fab" user "Ref Des/Assembly Top")
		(33 "B.Fab" user "Ref Des/Assembly Bottom")
	)
	(footprint ""
		(layer "F.Cu")
		(at 393.316206 -155.356052 -90)
		(property "Reference" "U30"
			(at 0.617474 -3.043174 0)
			(unlocked yes)
			(layer "F.SilkS")
			(effects
				(font
					(size 0.7874 0.5842)
					(thickness 0.1524)
				)
				(justify left)
			)
		)
		(property "Value" ""
			(at 0 0 270)
			(layer "F.Fab")
			(effects
				(font
					(size 1.27 1.27)
				)
			)
		)
		(duplicate_pad_numbers_are_jumpers no)
		(fp_line
			(start -1.4224 2.5146)
			(end 1.4224 2.5146)
			(stroke
				(width 0.1524)
				(type default)
			)
			(layer "F.SilkS")
		)
		(fp_line
			(start 1.4224 2.5146)
			(end 1.4224 -2.5146)
			(stroke
				(width 0.1524)
				(type default)
			)
			(layer "F.SilkS")
		)
		(fp_line
			(start 0 -2.0574)
			(end -0.4572 -2.5146)
			(stroke
				(width 0.1524)
				(type default)
			)
			(layer "F.SilkS")
		)
		(fp_line
			(start -1.4224 -2.5146)
			(end -1.4224 2.5146)
			(stroke
				(width 0.1524)
				(type default)
			)
			(layer "F.SilkS")
		)
		(fp_line
			(start -0.4572 -2.5146)
			(end -1.4224 -2.5146)
			(stroke
				(width 0.1524)
				(type default)
			)
			(layer "F.SilkS")
		)
		(fp_line
			(start 0.4572 -2.5146)
			(end 0 -2.0574)
			(stroke
				(width 0.1524)
				(type default)
			)
			(layer "F.SilkS")
		)
		(fp_line
			(start 1.4224 -2.5146)
			(end 0.4572 -2.5146)
			(stroke
				(width 0.1524)
				(type default)
			)
			(layer "F.SilkS")
		)
		(fp_poly
			(pts
				(xy -3.080004 -3.230118) (xy -2.318004 -3.230118) (xy -2.699004 -2.468118)
			)
			(stroke
				(width 0)
				(type default)
			)
			(fill yes)
			(layer "F.SilkS")
		)
		(fp_line
			(start -2.0066 2.5146)
			(end 2.0066 2.5146)
			(stroke
				(width 0.1)
				(type default)
			)
			(layer "F.Fab")
		)
		(fp_line
			(start 2.0066 2.5146)
			(end 2.0066 2.112264)
			(stroke
				(width 0.1)
				(type default)
			)
			(layer "F.Fab")
		)
		(fp_line
			(start -2.648712 2.112264)
			(end -2.0066 2.112264)
			(stroke
				(width 0.1)
				(type default)
			)
			(layer "F.Fab")
		)
		(fp_line
			(start -2.0066 2.112264)
			(end -2.0066 2.5146)
			(stroke
				(width 0.1)
				(type default)
			)
			(layer "F.Fab")
		)
		(fp_line
			(start 2.0066 2.112264)
			(end 2.642616 2.112264)
			(stroke
				(width 0.1)
				(type default)
			)
			(layer "F.Fab")
		)
		(fp_line
			(start 2.642616 2.112264)
			(end 2.642616 -2.112264)
			(stroke
				(width 0.1)
				(type default)
			)
			(layer "F.Fab")
		)
		(fp_line
			(start 2.0066 -2.112264)
			(end 2.0066 -2.5146)
			(stroke
				(width 0.1)
				(type default)
			)
			(layer "F.Fab")
		)
		(fp_line
			(start 2.642616 -2.112264)
			(end 2.0066 -2.112264)
			(stroke
				(width 0.1)
				(type default)
			)
			(layer "F.Fab")
		)
		(fp_line
			(start -2.648712 -2.114804)
			(end -2.648712 2.112264)
			(stroke
				(width 0.1)
				(type default)
			)
			(layer "F.Fab")
		)
		(fp_line
			(start -2.0066 -2.114804)
			(end -2.648712 -2.114804)
			(stroke
				(width 0.1)
				(type default)
			)
			(layer "F.Fab")
		)
		(fp_line
			(start -2.0066 -2.5146)
			(end -2.0066 -2.114804)
			(stroke
				(width 0.1)
				(type default)
			)
			(layer "F.Fab")
		)
		(fp_line
			(start 2.0066 -2.5146)
			(end -2.0066 -2.5146)
			(stroke
				(width 0.1)
				(type default)
			)
			(layer "F.Fab")
		)
		(fp_poly
			(pts
				(xy -3.6322 -1.869186) (xy -4.3942 -1.488186) (xy -4.3942 -2.250186)
			)
			(stroke
				(width 0)
				(type default)
			)
			(fill yes)
			(layer "F.Fab")
		)
		(pad "1" smd rect
			(at -2.6416 -1.905 180)
			(size 0.5588 1.7272)
			(layers "F.Cu" "F.Mask" "F.Paste")
			(net "PVNN_TERM_CPU0")
		)
		(pad "2" smd rect
			(at -2.6416 -0.635 180)
			(size 0.5588 1.7272)
			(layers "F.Cu" "F.Mask" "F.Paste")
			(net "SMB_S3M_CPU0_R_SCL")
		)
		(pad "3" smd rect
			(at -2.6416 0.635 180)
			(size 0.5588 1.7272)
			(layers "F.Cu" "F.Mask" "F.Paste")
			(net "SMB_S3M_CPU0_R_SDA")
		)
		(pad "4" smd rect
			(at -2.6416 1.905 180)
			(size 0.5588 1.7272)
			(layers "F.Cu" "F.Mask" "F.Paste")
			(net "GND")
		)
		(pad "5" smd rect
			(at 2.6416 1.905 180)
			(size 0.5588 1.7272)
			(layers "F.Cu" "F.Mask" "F.Paste")
			(net "TP_SMB_S3M_CPU0_EN")
		)
		(pad "6" smd rect
			(at 2.6416 0.635 180)
			(size 0.5588 1.7272)
			(layers "F.Cu" "F.Mask" "F.Paste")
			(net "SMB_S3M_CPU0_3V3AUX_SDA")
		)
		(pad "7" smd rect
			(at 2.6416 -0.635 180)
			(size 0.5588 1.7272)
			(layers "F.Cu" "F.Mask" "F.Paste")
			(net "SMB_S3M_CPU0_3V3AUX_SCL")
		)
		(pad "8" smd rect
			(at 2.6416 -1.905 180)
			(size 0.5588 1.7272)
			(layers "F.Cu" "F.Mask" "F.Paste")
			(net "P3V3_AUX")
		)
	)
	(footprint ""
		(layer "F.Cu")
		(at 170.23588 -126.964948 90)
		(property "Reference" "R984"
			(at 0 0 90)
			(layer "F.SilkS")
			(hide yes)
			(effects
				(font
					(size 1.27 1.27)
				)
			)
		)
		(property "Value" ""
			(at 0 0 90)
			(layer "F.Fab")
			(effects
				(font
					(size 1.27 1.27)
				)
			)
		)
		(duplicate_pad_numbers_are_jumpers no)
		(fp_line
			(start 0.7874 -0.4064)
			(end 0.7874 0.4064)
			(stroke
				(width 0.1524)
				(type default)
			)
			(layer "F.SilkS")
		)
		(fp_line
			(start -0.7874 -0.4064)
			(end 0.7874 -0.4064)
			(stroke
				(width 0.1524)
				(type default)
			)
			(layer "F.SilkS")
		)
		(fp_line
			(start 0.7874 0.4064)
			(end -0.7874 0.4064)
			(stroke
				(width 0.1524)
				(type default)
			)
			(layer "F.SilkS")
		)
		(fp_line
			(start -0.7874 0.4064)
			(end -0.7874 -0.4064)
			(stroke
				(width 0.1524)
				(type default)
			)
			(layer "F.SilkS")
		)
		(fp_line
			(start -0.12065 -0.305054)
			(end -0.12065 -0.2794)
			(stroke
				(width 0.1)
				(type default)
			)
			(layer "F.Fab")
		)
		(fp_line
			(start -0.67945 -0.305054)
			(end -0.12065 -0.305054)
			(stroke
				(width 0.1)
				(type default)
			)
			(layer "F.Fab")
		)
		(fp_line
			(start 0.67945 -0.3048)
			(end 0.67945 0.3048)
			(stroke
				(width 0.1)
				(type default)
			)
			(layer "F.Fab")
		)
		(fp_line
			(start 0.12065 -0.3048)
			(end 0.67945 -0.3048)
			(stroke
				(width 0.1)
				(type default)
			)
			(layer "F.Fab")
		)
		(fp_line
			(start 0.12065 -0.2794)
			(end 0.12065 -0.3048)
			(stroke
				(width 0.1)
				(type default)
			)
			(layer "F.Fab")
		)
		(fp_line
			(start -0.12065 -0.2794)
			(end 0.12065 -0.2794)
			(stroke
				(width 0.1)
				(type default)
			)
			(layer "F.Fab")
		)
		(fp_line
			(start 0.120396 0.2794)
			(end -0.12065 0.2794)
			(stroke
				(width 0.1)
				(type default)
			)
			(layer "F.Fab")
		)
		(fp_line
			(start -0.12065 0.2794)
			(end -0.12065 0.3048)
			(stroke
				(width 0.1)
				(type default)
			)
			(layer "F.Fab")
		)
		(fp_line
			(start 0.67945 0.3048)
			(end 0.120396 0.3048)
			(stroke
				(width 0.1)
				(type default)
			)
			(layer "F.Fab")
		)
		(fp_line
			(start 0.120396 0.3048)
			(end 0.120396 0.2794)
			(stroke
				(width 0.1)
				(type default)
			)
			(layer "F.Fab")
		)
		(fp_line
			(start -0.12065 0.3048)
			(end -0.67945 0.3048)
			(stroke
				(width 0.1)
				(type default)
			)
			(layer "F.Fab")
		)
		(fp_line
			(start -0.67945 0.3048)
			(end -0.67945 -0.305054)
			(stroke
				(width 0.1)
				(type default)
			)
			(layer "F.Fab")
		)
		(pad "1" smd circle
			(at -0.40005 0 90)
			(size 0 0)
			(layers "F.Cu" "F.Mask" "F.Paste")
			(net "FM_PVCCFA_EHV_FIVRA_CPU0_R_EN")
		)
		(pad "2" smd circle
			(at 0.40005 0 90)
			(size 0 0)
			(layers "F.Cu" "F.Mask" "F.Paste")
			(net "FM_PVCCFA_EHV_FIVRA_CPU0_EN")
		)
	)
)
